# T6G (Grand Teton) — schematic netlist excerpt (pin names and nets, part order shuffled) for the footprints in the layout excerpt that follows; sources: Cadence DE-HDL packaged netlist, KiCad conversion of 04192023_DAF0TMB3IC0_F0TG_MB_C_brd_V02_OCP.brd

C2435  Q_CAP  22UF 4V 20% X6S  pkg C0402  page 74 : A = PVDDCR_SOC_P1 ; B = GND
R1033  Q_RES  4.7K 5% CHIP  pkg 0201LF  page 287 : A = TEST1_RT_CPU0_P1 ; B = GND
C2211  Q_CAP  22UF 4V 20% X6S  pkg C0402  page 69 : A = PVDDCR_CPU1_P0 ; B = GND

(kicad_pcb
	(version 20260206)
	(generator "pcbnew")
	(generator_version "10.0")
	(general
		(thickness 1.6)
		(legacy_teardrops no)
	)
	(paper "A4")
	(title_block
		(title "04192023_DAF0TMB3IC0_F0TG_MB_C_brd_V02_OCP.brd")
		(comment 1 "Grand Teton / footprints 7245-7247 of 8354")
	)
	(layers
		(0 "F.Cu" signal "TOP")
		(4 "In1.Cu" signal "GND")
		(6 "In2.Cu" signal "IN1")
		(8 "In3.Cu" signal "GND1")
		(10 "In4.Cu" signal "IN2")
		(12 "In5.Cu" signal "GND2")
		(14 "In6.Cu" signal "IN3")
		(16 "In7.Cu" signal "GND3")
		(18 "In8.Cu" signal "VCC")
		(20 "In9.Cu" signal "VCC1")
		(22 "In10.Cu" signal "GND4")
		(24 "In11.Cu" signal "IN4")
		(26 "In12.Cu" signal "GND5")
		(28 "In13.Cu" signal "IN5")
		(30 "In14.Cu" signal "GND6")
		(32 "In15.Cu" signal "IN6")
		(34 "In16.Cu" signal "GND7")
		(2 "B.Cu" signal "BOTTOM")
		(9 "F.Adhes" user "F.Adhesive")
		(11 "B.Adhes" user "B.Adhesive")
		(13 "F.Paste" user "Package Geometry/Pastemask Top")
		(15 "B.Paste" user "Package Geometry/Pastemask Bottom")
		(5 "F.SilkS" user "Ref Des/Silkscreen Top")
		(7 "B.SilkS" user "Ref Des/Silkscreen Bottom")
		(1 "F.Mask" user "Board Geometry/Soldermask Top")
		(3 "B.Mask" user "Board Geometry/Soldermask Bottom")
		(17 "Dwgs.User" user "User.Drawings")
		(19 "Cmts.User" user "User.Comments")
		(21 "Eco1.User" user "User.Eco1")
		(23 "Eco2.User" user "User.Eco2")
		(25 "Edge.Cuts" user "Board Geometry/Outline")
		(27 "Margin" user)
		(31 "F.CrtYd" user "Package Geometry/Place Bound Top")
		(29 "B.CrtYd" user "Package Geometry/Place Bound Bottom")
		(35 "F.Fab" user "Ref Des/Assembly Top")
		(33 "B.Fab" user "Ref Des/Assembly Bottom")
	)
	(footprint ""
		(layer "B.Cu")
		(at 367.614454 -267.498576)
		(property "Reference" "C2211"
			(at 0 0 0)
			(layer "B.SilkS")
			(hide yes)
			(effects
				(font
					(size 1.27 1.27)
				)
				(justify mirror)
			)
		)
		(property "Value" ""
			(at 0 0 0)
			(layer "B.Fab")
			(effects
				(font
					(size 1.27 1.27)
				)
				(justify mirror)
			)
		)
		(duplicate_pad_numbers_are_jumpers no)
		(fp_line
			(start -0.7874 -0.4064)
			(end -0.7874 0.4064)
			(stroke
				(width 0.1524)
				(type default)
			)
			(layer "B.SilkS")
		)
		(fp_line
			(start -0.7874 0.4064)
			(end 0.7874 0.4064)
			(stroke
				(width 0.1524)
				(type default)
			)
			(layer "B.SilkS")
		)
		(fp_line
			(start 0.7874 -0.4064)
			(end -0.7874 -0.4064)
			(stroke
				(width 0.1524)
				(type default)
			)
			(layer "B.SilkS")
		)
		(fp_line
			(start 0.7874 0.4064)
			(end 0.7874 -0.4064)
			(stroke
				(width 0.1524)
				(type default)
			)
			(layer "B.SilkS")
		)
		(fp_line
			(start -0.67945 -0.3048)
			(end -0.67945 0.3048)
			(stroke
				(width 0.1)
				(type default)
			)
			(layer "B.Fab")
		)
		(fp_line
			(start -0.67945 0.3048)
			(end -0.120396 0.3048)
			(stroke
				(width 0.1)
				(type default)
			)
			(layer "B.Fab")
		)
		(fp_line
			(start -0.12065 -0.3048)
			(end -0.67945 -0.3048)
			(stroke
				(width 0.1)
				(type default)
			)
			(layer "B.Fab")
		)
		(fp_line
			(start -0.12065 -0.2794)
			(end -0.12065 -0.3048)
			(stroke
				(width 0.1)
				(type default)
			)
			(layer "B.Fab")
		)
		(fp_line
			(start -0.120396 0.2794)
			(end 0.12065 0.2794)
			(stroke
				(width 0.1)
				(type default)
			)
			(layer "B.Fab")
		)
		(fp_line
			(start -0.120396 0.3048)
			(end -0.120396 0.2794)
			(stroke
				(width 0.1)
				(type default)
			)
			(layer "B.Fab")
		)
		(fp_line
			(start 0.12065 -0.305054)
			(end 0.12065 -0.2794)
			(stroke
				(width 0.1)
				(type default)
			)
			(layer "B.Fab")
		)
		(fp_line
			(start 0.12065 -0.2794)
			(end -0.12065 -0.2794)
			(stroke
				(width 0.1)
				(type default)
			)
			(layer "B.Fab")
		)
		(fp_line
			(start 0.12065 0.2794)
			(end 0.12065 0.3048)
			(stroke
				(width 0.1)
				(type default)
			)
			(layer "B.Fab")
		)
		(fp_line
			(start 0.12065 0.3048)
			(end 0.67945 0.3048)
			(stroke
				(width 0.1)
				(type default)
			)
			(layer "B.Fab")
		)
		(fp_line
			(start 0.67945 -0.305054)
			(end 0.12065 -0.305054)
			(stroke
				(width 0.1)
				(type default)
			)
			(layer "B.Fab")
		)
		(fp_line
			(start 0.67945 0.3048)
			(end 0.67945 -0.305054)
			(stroke
				(width 0.1)
				(type default)
			)
			(layer "B.Fab")
		)
		(pad "1" smd circle
			(at 0.40005 0 180)
			(size 0 0)
			(layers "B.Cu" "B.Mask" "B.Paste")
			(net "PVDDCR_CPU1_P0")
		)
		(pad "2" smd circle
			(at -0.40005 0 180)
			(size 0 0)
			(layers "B.Cu" "B.Mask" "B.Paste")
			(net "GND")
		)
	)
	(footprint ""
		(layer "B.Cu")
		(at 331.793342 -393.04468 180)
		(property "Reference" "R1033"
			(at 0 0 0)
			(layer "B.SilkS")
			(hide yes)
			(effects
				(font
					(size 1.27 1.27)
				)
				(justify mirror)
			)
		)
		(property "Value" ""
			(at 0 0 0)
			(layer "B.Fab")
			(effects
				(font
					(size 1.27 1.27)
				)
				(justify mirror)
			)
		)
		(duplicate_pad_numbers_are_jumpers no)
		(fp_line
			(start 0.32512 0.175006)
			(end 0.32512 -0.175006)
			(stroke
				(width 0.1)
				(type default)
			)
			(layer "B.Fab")
		)
		(fp_line
			(start 0.32512 -0.175006)
			(end -0.32512 -0.175006)
			(stroke
				(width 0.1)
				(type default)
			)
			(layer "B.Fab")
		)
		(fp_line
			(start -0.32512 0.175006)
			(end 0.32512 0.175006)
			(stroke
				(width 0.1)
				(type default)
			)
			(layer "B.Fab")
		)
		(fp_line
			(start -0.32512 -0.175006)
			(end -0.32512 0.175006)
			(stroke
				(width 0.1)
				(type default)
			)
			(layer "B.Fab")
		)
		(pad "1" smd rect
			(at 0.2667 0)
			(size 0.3048 0.381)
			(layers "B.Cu" "B.Mask" "B.Paste")
			(net "TEST1_RT_CPU0_P1")
		)
		(pad "2" smd rect
			(at -0.2667 0 180)
			(size 0.3048 0.381)
			(layers "B.Cu" "B.Mask" "B.Paste")
			(net "GND")
		)
	)
	(footprint ""
		(layer "B.Cu")
		(at 124.741432 -261.93623)
		(property "Reference" "C2435"
			(at 0 0 0)
			(layer "B.SilkS")
			(hide yes)
			(effects
				(font
					(size 1.27 1.27)
				)
				(justify mirror)
			)
		)
		(property "Value" ""
			(at 0 0 0)
			(layer "B.Fab")
			(effects
				(font
					(size 1.27 1.27)
				)
				(justify mirror)
			)
		)
		(duplicate_pad_numbers_are_jumpers no)
		(fp_line
			(start -0.7874 -0.4064)
			(end -0.7874 0.4064)
			(stroke
				(width 0.1524)
				(type default)
			)
			(layer "B.SilkS")
		)
		(fp_line
			(start -0.7874 0.4064)
			(end 0.7874 0.4064)
			(stroke
				(width 0.1524)
				(type default)
			)
			(layer "B.SilkS")
		)
		(fp_line
			(start 0.7874 -0.4064)
			(end -0.7874 -0.4064)
			(stroke
				(width 0.1524)
				(type default)
			)
			(layer "B.SilkS")
		)
		(fp_line
			(start 0.7874 0.4064)
			(end 0.7874 -0.4064)
			(stroke
				(width 0.1524)
				(type default)
			)
			(layer "B.SilkS")
		)
		(fp_line
			(start -0.67945 -0.3048)
			(end -0.67945 0.3048)
			(stroke
				(width 0.1)
				(type default)
			)
			(layer "B.Fab")
		)
		(fp_line
			(start -0.67945 0.3048)
			(end -0.120396 0.3048)
			(stroke
				(width 0.1)
				(type default)
			)
			(layer "B.Fab")
		)
		(fp_line
			(start -0.12065 -0.3048)
			(end -0.67945 -0.3048)
			(stroke
				(width 0.1)
				(type default)
			)
			(layer "B.Fab")
		)
		(fp_line
			(start -0.12065 -0.2794)
			(end -0.12065 -0.3048)
			(stroke
				(width 0.1)
				(type default)
			)
			(layer "B.Fab")
		)
		(fp_line
			(start -0.120396 0.2794)
			(end 0.12065 0.2794)
			(stroke
				(width 0.1)
				(type default)
			)
			(layer "B.Fab")
		)
		(fp_line
			(start -0.120396 0.3048)
			(end -0.120396 0.2794)
			(stroke
				(width 0.1)
				(type default)
			)
			(layer "B.Fab")
		)
		(fp_line
			(start 0.12065 -0.305054)
			(end 0.12065 -0.2794)
			(stroke
				(width 0.1)
				(type default)
			)
			(layer "B.Fab")
		)
		(fp_line
			(start 0.12065 -0.2794)
			(end -0.12065 -0.2794)
			(stroke
				(width 0.1)
				(type default)
			)
			(layer "B.Fab")
		)
		(fp_line
			(start 0.12065 0.2794)
			(end 0.12065 0.3048)
			(stroke
				(width 0.1)
				(type default)
			)
			(layer "B.Fab")
		)
		(fp_line
			(start 0.12065 0.3048)
			(end 0.67945 0.3048)
			(stroke
				(width 0.1)
				(type default)
			)
			(layer "B.Fab")
		)
		(fp_line
			(start 0.67945 -0.305054)
			(end 0.12065 -0.305054)
			(stroke
				(width 0.1)
				(type default)
			)
			(layer "B.Fab")
		)
		(fp_line
			(start 0.67945 0.3048)
			(end 0.67945 -0.305054)
			(stroke
				(width 0.1)
				(type default)
			)
			(layer "B.Fab")
		)
		(pad "1" smd circle
			(at 0.40005 0 180)
			(size 0 0)
			(layers "B.Cu" "B.Mask" "B.Paste")
			(net "PVDDCR_SOC_P1")
		)
		(pad "2" smd circle
			(at -0.40005 0 180)
			(size 0 0)
			(layers "B.Cu" "B.Mask" "B.Paste")
			(net "GND")
		)
	)
)
